(kicad_pcb
	(version 20260206)
	(generator "pcbnew")
	(generator_version "10.0")
	(general
		(thickness 1.6)
		(legacy_teardrops no)
	)
	(paper "A4")
	(title_block
		(title "timecard-production-celestica-r4006 — R4006-B0001-02_R01.brd")
		(comment 1 "Time Appliance Project (Time Card) / footprints 698-702 of 1113")
	)
	(layers
		(0 "F.Cu" signal "TOP")
		(4 "In1.Cu" signal "L02_GND1")
		(6 "In2.Cu" signal "L03_SIG1")
		(8 "In3.Cu" signal "L04_GND2")
		(10 "In4.Cu" signal "L05_VCC1")
		(12 "In5.Cu" signal "L06_VCC2")
		(14 "In6.Cu" signal "L07_GND3")
		(16 "In7.Cu" signal "L08_SIG2")
		(18 "In8.Cu" signal "L09_GND4")
		(2 "B.Cu" signal "BOTTOM")
		(9 "F.Adhes" user "F.Adhesive")
		(11 "B.Adhes" user "B.Adhesive")
		(13 "F.Paste" user "Package Geometry/Pastemask Top")
		(15 "B.Paste" user "Package Geometry/Pastemask Bottom")
		(5 "F.SilkS" user "Ref Des/Silkscreen Top")
		(7 "B.SilkS" user "Ref Des/Silkscreen Bottom")
		(1 "F.Mask" user "Board Geometry/Soldermask Top")
		(3 "B.Mask" user "Board Geometry/Soldermask Bottom")
		(17 "Dwgs.User" user "User.Drawings")
		(19 "Cmts.User" user "User.Comments")
		(21 "Eco1.User" user "User.Eco1")
		(23 "Eco2.User" user "User.Eco2")
		(25 "Edge.Cuts" user "Board Geometry/Outline")
		(27 "Margin" user)
		(31 "F.CrtYd" user "Package Geometry/Place Bound Top")
		(29 "B.CrtYd" user "Package Geometry/Place Bound Bottom")
		(35 "F.Fab" user "Ref Des/Assembly Top")
		(33 "B.Fab" user "Ref Des/Assembly Bottom")
	)
	(footprint ""
		(layer "B.Cu")
		(at 28.702 -91.059 -90)
		(property "Reference" "C100"
			(at -3.175 -0.08763 270)
			(unlocked yes)
			(layer "B.SilkS")
			(effects
				(font
					(size 0.7874 0.5842)
					(thickness 0.1524)
				)
				(justify mirror)
			)
		)
		(property "Value" "VAL*"
			(at -0.0762 2.067306 270)
			(unlocked yes)
			(layer "B.Fab")
			(hide yes)
			(effects
				(font
					(size 0.7874 0.5842)
					(thickness 0.1524)
				)
				(justify mirror)
			)
		)
		(property "Tolerance" "TOL*"
			(at -0.0762 3.032506 270)
			(unlocked yes)
			(layer "Cmts.User")
			(hide yes)
			(effects
				(font
					(size 0.7874 0.5842)
					(thickness 0.1524)
				)
				(justify mirror)
			)
		)
		(property "User Part Number" "PARTNUM*"
			(at -0.1016 4.023106 270)
			(unlocked yes)
			(layer "Cmts.User")
			(hide yes)
			(effects
				(font
					(size 0.7874 0.5842)
					(thickness 0.1524)
				)
				(justify mirror)
			)
		)
		(property "Device Type" "CAPACITOR-G105-0B104-EK,0.1UF,A"
			(at -0.0508 1.127506 270)
			(unlocked yes)
			(layer "B.Fab")
			(hide yes)
			(effects
				(font
					(size 0.7874 0.5842)
					(thickness 0.1524)
				)
				(justify mirror)
			)
		)
		(duplicate_pad_numbers_are_jumpers no)
		(fp_line
			(start -1.143 0.5588)
			(end -1.143 -0.5588)
			(stroke
				(width 0.1)
				(type default)
			)
			(layer "B.SilkS")
		)
		(fp_line
			(start 1.143 0.5588)
			(end -1.143 0.5588)
			(stroke
				(width 0.1)
				(type default)
			)
			(layer "B.SilkS")
		)
		(fp_line
			(start -1.143 -0.5588)
			(end 1.143 -0.5588)
			(stroke
				(width 0.1)
				(type default)
			)
			(layer "B.SilkS")
		)
		(fp_line
			(start 1.143 -0.5588)
			(end 1.143 0.5588)
			(stroke
				(width 0.1)
				(type default)
			)
			(layer "B.SilkS")
		)
		(fp_rect
			(start 1.143 -0.5588)
			(end -1.143 0.5588)
			(stroke
				(width 0)
				(type default)
			)
			(fill no)
			(layer "B.CrtYd")
		)
		(fp_line
			(start -0.508 0.3048)
			(end -0.508 -0.3048)
			(stroke
				(width 0.1)
				(type default)
			)
			(layer "B.Fab")
		)
		(fp_line
			(start 0.508 0.3048)
			(end -0.508 0.3048)
			(stroke
				(width 0.1)
				(type default)
			)
			(layer "B.Fab")
		)
		(fp_line
			(start -0.508 -0.3048)
			(end 0.508 -0.3048)
			(stroke
				(width 0.1)
				(type default)
			)
			(layer "B.Fab")
		)
		(fp_line
			(start 0.508 -0.3048)
			(end 0.508 0.3048)
			(stroke
				(width 0.1)
				(type default)
			)
			(layer "B.Fab")
		)
		(pad "1" smd rect
			(at 0.5334 0 90)
			(size 0.7112 0.6096)
			(layers "B.Cu" "B.Mask" "B.Paste")
			(net "XP3R3V_VPLL")
		)
		(pad "2" smd rect
			(at -0.5334 0 90)
			(size 0.7112 0.6096)
			(layers "B.Cu" "B.Mask" "B.Paste")
			(net "SG")
		)
		(zone
			(layer "B.Cu")
			(hatch none 0.5)
			(connect_pads
				(clearance 0)
			)
			(min_thickness 0.25)
			(keepout
				(tracks allowed)
				(vias not_allowed)
				(pads allowed)
				(copperpour not_allowed)
				(footprints allowed)
			)
			(placement
				(enabled no)
				(sheetname "")
			)
			(fill
				(thermal_gap 0.5)
				(thermal_bridge_width 0.5)
				(island_removal_mode 0)
			)
			(polygon
				(pts
					(xy 29.0068 -90.9828) (xy 29.0068 -91.1352) (xy 28.3972 -91.1352) (xy 28.3972 -90.9828)
				)
			)
		)
	)
	(footprint ""
		(layer "B.Cu")
		(at 98.044 -64.2874 90)
		(property "Reference" "R284"
			(at 3.4036 0.21463 270)
			(unlocked yes)
			(layer "B.SilkS")
			(effects
				(font
					(size 0.7874 0.5842)
					(thickness 0.1524)
				)
				(justify mirror)
			)
		)
		(property "Value" "VAL*"
			(at -0.02032 2.13233 90)
			(unlocked yes)
			(layer "B.Fab")
			(hide yes)
			(effects
				(font
					(size 0.7874 0.5842)
					(thickness 0.1524)
				)
				(justify mirror)
			)
		)
		(property "Tolerance" "TOL*"
			(at -0.044704 3.05435 90)
			(unlocked yes)
			(layer "Cmts.User")
			(hide yes)
			(effects
				(font
					(size 0.7874 0.5842)
					(thickness 0.1524)
				)
				(justify mirror)
			)
		)
		(property "User Part Number" "PARTNUM*"
			(at -0.02032 4.024884 90)
			(unlocked yes)
			(layer "Cmts.User")
			(hide yes)
			(effects
				(font
					(size 0.7874 0.5842)
					(thickness 0.1524)
				)
				(justify mirror)
			)
		)
		(property "Device Type" "RESISTOR-G155-14701-01,4.7KOHMA"
			(at -0.008382 1.210564 90)
			(unlocked yes)
			(layer "B.Fab")
			(hide yes)
			(effects
				(font
					(size 0.7874 0.5842)
					(thickness 0.1524)
				)
				(justify mirror)
			)
		)
		(duplicate_pad_numbers_are_jumpers no)
		(fp_line
			(start 1.143 -0.5588)
			(end 1.143 0.5588)
			(stroke
				(width 0.1)
				(type default)
			)
			(layer "B.SilkS")
		)
		(fp_line
			(start -1.143 -0.5588)
			(end 1.143 -0.5588)
			(stroke
				(width 0.1)
				(type default)
			)
			(layer "B.SilkS")
		)
		(fp_line
			(start 1.143 0.5588)
			(end -1.143 0.5588)
			(stroke
				(width 0.1)
				(type default)
			)
			(layer "B.SilkS")
		)
		(fp_line
			(start -1.143 0.5588)
			(end -1.143 -0.5588)
			(stroke
				(width 0.1)
				(type default)
			)
			(layer "B.SilkS")
		)
		(fp_poly
			(pts
				(xy 1.143 0.5588) (xy -1.143 0.5588) (xy -1.143 -0.5588) (xy 1.143 -0.5588)
			)
			(stroke
				(width 0)
				(type default)
			)
			(fill no)
			(layer "B.CrtYd")
		)
		(fp_line
			(start 0.508 -0.3048)
			(end 0.508 0.3048)
			(stroke
				(width 0.1)
				(type default)
			)
			(layer "B.Fab")
		)
		(fp_line
			(start -0.508 -0.3048)
			(end 0.508 -0.3048)
			(stroke
				(width 0.1)
				(type default)
			)
			(layer "B.Fab")
		)
		(fp_line
			(start 0.508 0.3048)
			(end -0.508 0.3048)
			(stroke
				(width 0.1)
				(type default)
			)
			(layer "B.Fab")
		)
		(fp_line
			(start -0.508 0.3048)
			(end -0.508 -0.3048)
			(stroke
				(width 0.1)
				(type default)
			)
			(layer "B.Fab")
		)
		(pad "1" smd rect
			(at 0.5334 0 270)
			(size 0.7112 0.6096)
			(layers "B.Cu" "B.Mask" "B.Paste")
			(net "SG")
		)
		(pad "2" smd rect
			(at -0.5334 0 270)
			(size 0.7112 0.6096)
			(layers "B.Cu" "B.Mask" "B.Paste")
			(net "FPGA_IO_2")
		)
		(zone
			(layer "B.Cu")
			(hatch none 0.5)
			(connect_pads
				(clearance 0)
			)
			(min_thickness 0.25)
			(keepout
				(tracks not_allowed)
				(vias allowed)
				(pads allowed)
				(copperpour not_allowed)
				(footprints allowed)
			)
			(placement
				(enabled no)
				(sheetname "")
			)
			(fill
				(thermal_gap 0.5)
				(thermal_bridge_width 0.5)
				(island_removal_mode 0)
			)
			(polygon
				(pts
					(xy 98.3488 -64.3636) (xy 97.7392 -64.3636) (xy 97.7392 -64.2112) (xy 98.3488 -64.2112)
				)
			)
		)
		(zone
			(layer "B.Cu")
			(hatch none 0.5)
			(connect_pads
				(clearance 0)
			)
			(min_thickness 0.25)
			(keepout
				(tracks allowed)
				(vias not_allowed)
				(pads allowed)
				(copperpour not_allowed)
				(footprints allowed)
			)
			(placement
				(enabled no)
				(sheetname "")
			)
			(fill
				(thermal_gap 0.5)
				(thermal_bridge_width 0.5)
				(island_removal_mode 0)
			)
			(polygon
				(pts
					(xy 98.3488 -64.3636) (xy 97.7392 -64.3636) (xy 97.7392 -64.2112) (xy 98.3488 -64.2112)
				)
			)
		)
	)
	(footprint ""
		(layer "B.Cu")
		(at 150.114 -104.394 90)
		(property "Reference" "R118"
			(at -1.397 1.10363 270)
			(unlocked yes)
			(layer "B.SilkS")
			(effects
				(font
					(size 0.7874 0.5842)
					(thickness 0.1524)
				)
				(justify mirror)
			)
		)
		(property "Value" "VAL*"
			(at -0.02032 2.13233 90)
			(unlocked yes)
			(layer "B.Fab")
			(hide yes)
			(effects
				(font
					(size 0.7874 0.5842)
					(thickness 0.1524)
				)
				(justify mirror)
			)
		)
		(property "Tolerance" "TOL*"
			(at -0.044704 3.05435 90)
			(unlocked yes)
			(layer "Cmts.User")
			(hide yes)
			(effects
				(font
					(size 0.7874 0.5842)
					(thickness 0.1524)
				)
				(justify mirror)
			)
		)
		(property "User Part Number" "PARTNUM*"
			(at -0.02032 4.024884 90)
			(unlocked yes)
			(layer "Cmts.User")
			(hide yes)
			(effects
				(font
					(size 0.7874 0.5842)
					(thickness 0.1524)
				)
				(justify mirror)
			)
		)
		(property "Device Type" "RESISTOR-G155-13300-01,330OHM,A"
			(at -0.008382 1.210564 90)
			(unlocked yes)
			(layer "B.Fab")
			(hide yes)
			(effects
				(font
					(size 0.7874 0.5842)
					(thickness 0.1524)
				)
				(justify mirror)
			)
		)
		(duplicate_pad_numbers_are_jumpers no)
		(fp_line
			(start 1.143 -0.5588)
			(end 1.143 0.5588)
			(stroke
				(width 0.1)
				(type default)
			)
			(layer "B.SilkS")
		)
		(fp_line
			(start -1.143 -0.5588)
			(end 1.143 -0.5588)
			(stroke
				(width 0.1)
				(type default)
			)
			(layer "B.SilkS")
		)
		(fp_line
			(start 1.143 0.5588)
			(end -1.143 0.5588)
			(stroke
				(width 0.1)
				(type default)
			)
			(layer "B.SilkS")
		)
		(fp_line
			(start -1.143 0.5588)
			(end -1.143 -0.5588)
			(stroke
				(width 0.1)
				(type default)
			)
			(layer "B.SilkS")
		)
		(fp_poly
			(pts
				(xy 1.143 0.5588) (xy -1.143 0.5588) (xy -1.143 -0.5588) (xy 1.143 -0.5588)
			)
			(stroke
				(width 0)
				(type default)
			)
			(fill no)
			(layer "B.CrtYd")
		)
		(fp_line
			(start 0.508 -0.3048)
			(end 0.508 0.3048)
			(stroke
				(width 0.1)
				(type default)
			)
			(layer "B.Fab")
		)
		(fp_line
			(start -0.508 -0.3048)
			(end 0.508 -0.3048)
			(stroke
				(width 0.1)
				(type default)
			)
			(layer "B.Fab")
		)
		(fp_line
			(start 0.508 0.3048)
			(end -0.508 0.3048)
			(stroke
				(width 0.1)
				(type default)
			)
			(layer "B.Fab")
		)
		(fp_line
			(start -0.508 0.3048)
			(end -0.508 -0.3048)
			(stroke
				(width 0.1)
				(type default)
			)
			(layer "B.Fab")
		)
		(pad "1" smd rect
			(at 0.5334 0 270)
			(size 0.7112 0.6096)
			(layers "B.Cu" "B.Mask" "B.Paste")
			(net "UNNAMED_14_OPTICAL_I191_A")
		)
		(pad "2" smd rect
			(at -0.5334 0 270)
			(size 0.7112 0.6096)
			(layers "B.Cu" "B.Mask" "B.Paste")
			(net "XP3R3V_PCIE")
		)
		(zone
			(layer "B.Cu")
			(hatch none 0.5)
			(connect_pads
				(clearance 0)
			)
			(min_thickness 0.25)
			(keepout
				(tracks allowed)
				(vias not_allowed)
				(pads allowed)
				(copperpour not_allowed)
				(footprints allowed)
			)
			(placement
				(enabled no)
				(sheetname "")
			)
			(fill
				(thermal_gap 0.5)
				(thermal_bridge_width 0.5)
				(island_removal_mode 0)
			)
			(polygon
				(pts
					(xy 150.4188 -104.4702) (xy 149.8092 -104.4702) (xy 149.8092 -104.3178) (xy 150.4188 -104.3178)
				)
			)
		)
		(zone
			(layer "B.Cu")
			(hatch none 0.5)
			(connect_pads
				(clearance 0)
			)
			(min_thickness 0.25)
			(keepout
				(tracks not_allowed)
				(vias allowed)
				(pads allowed)
				(copperpour not_allowed)
				(footprints allowed)
			)
			(placement
				(enabled no)
				(sheetname "")
			)
			(fill
				(thermal_gap 0.5)
				(thermal_bridge_width 0.5)
				(island_removal_mode 0)
			)
			(polygon
				(pts
					(xy 150.4188 -104.4702) (xy 149.8092 -104.4702) (xy 149.8092 -104.3178) (xy 150.4188 -104.3178)
				)
			)
		)
	)
	(footprint ""
		(layer "B.Cu")
		(at 140.335 -71.501)
		(property "Reference" "R42"
			(at -4.191 -0.21463 0)
			(unlocked yes)
			(layer "B.SilkS")
			(effects
				(font
					(size 0.7874 0.5842)
					(thickness 0.1524)
				)
				(justify mirror)
			)
		)
		(property "Value" "VAL*"
			(at -0.02032 2.13233 0)
			(unlocked yes)
			(layer "B.Fab")
			(hide yes)
			(effects
				(font
					(size 0.7874 0.5842)
					(thickness 0.1524)
				)
				(justify mirror)
			)
		)
		(property "Tolerance" "TOL*"
			(at -0.044704 3.05435 0)
			(unlocked yes)
			(layer "Cmts.User")
			(hide yes)
			(effects
				(font
					(size 0.7874 0.5842)
					(thickness 0.1524)
				)
				(justify mirror)
			)
		)
		(property "User Part Number" "PARTNUM*"
			(at -0.02032 4.024884 0)
			(unlocked yes)
			(layer "Cmts.User")
			(hide yes)
			(effects
				(font
					(size 0.7874 0.5842)
					(thickness 0.1524)
				)
				(justify mirror)
			)
		)
		(property "Device Type" "RESISTOR-G155-100R0-J0,0OHM,-"
			(at -0.008382 1.210564 0)
			(unlocked yes)
			(layer "B.Fab")
			(hide yes)
			(effects
				(font
					(size 0.7874 0.5842)
					(thickness 0.1524)
				)
				(justify mirror)
			)
		)
		(duplicate_pad_numbers_are_jumpers no)
		(fp_line
			(start -1.143 -0.5588)
			(end 1.143 -0.5588)
			(stroke
				(width 0.1)
				(type default)
			)
			(layer "B.SilkS")
		)
		(fp_line
			(start -1.143 0.5588)
			(end -1.143 -0.5588)
			(stroke
				(width 0.1)
				(type default)
			)
			(layer "B.SilkS")
		)
		(fp_line
			(start 1.143 -0.5588)
			(end 1.143 0.5588)
			(stroke
				(width 0.1)
				(type default)
			)
			(layer "B.SilkS")
		)
		(fp_line
			(start 1.143 0.5588)
			(end -1.143 0.5588)
			(stroke
				(width 0.1)
				(type default)
			)
			(layer "B.SilkS")
		)
		(fp_rect
			(start 1.143 0.5588)
			(end -1.143 -0.5588)
			(stroke
				(width 0)
				(type default)
			)
			(fill no)
			(layer "B.CrtYd")
		)
		(fp_line
			(start -0.508 -0.3048)
			(end 0.508 -0.3048)
			(stroke
				(width 0.1)
				(type default)
			)
			(layer "B.Fab")
		)
		(fp_line
			(start -0.508 0.3048)
			(end -0.508 -0.3048)
			(stroke
				(width 0.1)
				(type default)
			)
			(layer "B.Fab")
		)
		(fp_line
			(start 0.508 -0.3048)
			(end 0.508 0.3048)
			(stroke
				(width 0.1)
				(type default)
			)
			(layer "B.Fab")
		)
		(fp_line
			(start 0.508 0.3048)
			(end -0.508 0.3048)
			(stroke
				(width 0.1)
				(type default)
			)
			(layer "B.Fab")
		)
		(pad "1" smd rect
			(at 0.5334 0 180)
			(size 0.7112 0.6096)
			(layers "B.Cu" "B.Mask" "B.Paste")
			(net "PCIE_CONN_TDO")
		)
		(pad "2" smd rect
			(at -0.5334 0 180)
			(size 0.7112 0.6096)
			(layers "B.Cu" "B.Mask" "B.Paste")
			(net "FPGA_TDO")
		)
		(zone
			(layer "B.Cu")
			(hatch none 0.5)
			(connect_pads
				(clearance 0)
			)
			(min_thickness 0.25)
			(keepout
				(tracks allowed)
				(vias not_allowed)
				(pads allowed)
				(copperpour not_allowed)
				(footprints allowed)
			)
			(placement
				(enabled no)
				(sheetname "")
			)
			(fill
				(thermal_gap 0.5)
				(thermal_bridge_width 0.5)
				(island_removal_mode 0)
			)
			(polygon
				(pts
					(xy 140.4112 -71.1962) (xy 140.4112 -71.8058) (xy 140.2588 -71.8058) (xy 140.2588 -71.1962)
				)
			)
		)
	)
	(footprint ""
		(layer "B.Cu")
		(at 109.475524 -48.704246 -90)
		(property "Reference" "C144"
			(at -0.063754 -0.982726 270)
			(unlocked yes)
			(layer "B.SilkS")
			(effects
				(font
					(size 0.635 0.4064)
					(thickness 0.1524)
				)
				(justify mirror)
			)
		)
		(property "Value" "VAL*"
			(at 0 3.718306 270)
			(unlocked yes)
			(layer "B.Fab")
			(hide yes)
			(effects
				(font
					(size 0.7874 0.5842)
					(thickness 0.127)
				)
				(justify mirror)
			)
		)
		(property "Device Type" "CAPACITOR-G105-0B104-CK,0.1UF,A"
			(at 0 1.432306 270)
			(unlocked yes)
			(layer "B.Fab")
			(hide yes)
			(effects
				(font
					(size 0.7874 0.5842)
					(thickness 0.127)
				)
				(justify mirror)
			)
		)
		(property "User Part Number" "PARTNUM*"
			(at 0 2.575306 270)
			(unlocked yes)
			(layer "Cmts.User")
			(hide yes)
			(effects
				(font
					(size 0.7874 0.5842)
					(thickness 0.127)
				)
				(justify mirror)
			)
		)
		(property "Tolerance" "TOL*"
			(at 0 4.861306 270)
			(unlocked yes)
			(layer "Cmts.User")
			(hide yes)
			(effects
				(font
					(size 0.7874 0.5842)
					(thickness 0.127)
				)
				(justify mirror)
			)
		)
		(duplicate_pad_numbers_are_jumpers no)
		(fp_line
			(start -0.970026 0.4699)
			(end 0.970026 0.4699)
			(stroke
				(width 0.1)
				(type default)
			)
			(layer "B.SilkS")
		)
		(fp_line
			(start 0.970026 0.4699)
			(end 0.970026 -0.4699)
			(stroke
				(width 0.1)
				(type default)
			)
			(layer "B.SilkS")
		)
		(fp_line
			(start -0.970026 -0.4699)
			(end -0.970026 0.4699)
			(stroke
				(width 0.1)
				(type default)
			)
			(layer "B.SilkS")
		)
		(fp_line
			(start 0.970026 -0.4699)
			(end -0.970026 -0.4699)
			(stroke
				(width 0.1)
				(type default)
			)
			(layer "B.SilkS")
		)
		(fp_poly
			(pts
				(xy 0.970026 0.4699) (xy -0.970026 0.4699) (xy -0.970026 -0.4699) (xy 0.970026 -0.4699)
			)
			(stroke
				(width 0)
				(type default)
			)
			(fill no)
			(layer "B.CrtYd")
		)
		(fp_line
			(start -0.508 0.3048)
			(end 0.508 0.3048)
			(stroke
				(width 0.1)
				(type default)
			)
			(layer "B.Fab")
		)
		(fp_line
			(start 0.508 0.3048)
			(end 0.508 -0.3048)
			(stroke
				(width 0.1)
				(type default)
			)
			(layer "B.Fab")
		)
		(fp_line
			(start -0.508 -0.3048)
			(end -0.508 0.3048)
			(stroke
				(width 0.1)
				(type default)
			)
			(layer "B.Fab")
		)
		(fp_line
			(start 0.508 -0.3048)
			(end -0.508 -0.3048)
			(stroke
				(width 0.1)
				(type default)
			)
			(layer "B.Fab")
		)
		(pad "1" smd circle
			(at 0.500126 0 90)
			(size 0.635 0.635)
			(layers "B.Cu" "B.Mask" "B.Paste")
			(net "XP3R3V_FPGA")
		)
		(pad "2" smd circle
			(at -0.500126 0 90)
			(size 0.635 0.635)
			(layers "B.Cu" "B.Mask" "B.Paste")
			(net "SG")
		)
	)
)
